(kicad_pcb
	(version 20260206)
	(generator "pcbnew")
	(generator_version "10.0")
	(general
		(thickness 1.6)
		(legacy_teardrops no)
	)
	(paper "A4")
	(title_block
		(title "Bryce Canyon_LED_16347-1_OCP.brd")
		(comment 1 "Bryce Canyon / footprints 24-30 of 49")
	)
	(layers
		(0 "F.Cu" signal "TOP")
		(2 "B.Cu" signal "BOTTOM")
		(9 "F.Adhes" user "F.Adhesive")
		(11 "B.Adhes" user "B.Adhesive")
		(13 "F.Paste" user "Package Geometry/Pastemask Top")
		(15 "B.Paste" user "Package Geometry/Pastemask Bottom")
		(5 "F.SilkS" user "Ref Des/Silkscreen Top")
		(7 "B.SilkS" user "Ref Des/Silkscreen Bottom")
		(1 "F.Mask" user "Board Geometry/Soldermask Top")
		(3 "B.Mask" user "Board Geometry/Soldermask Bottom")
		(17 "Dwgs.User" user "User.Drawings")
		(19 "Cmts.User" user "User.Comments")
		(21 "Eco1.User" user "User.Eco1")
		(23 "Eco2.User" user "User.Eco2")
		(25 "Edge.Cuts" user "Board Geometry/Outline")
		(27 "Margin" user)
		(31 "F.CrtYd" user "Package Geometry/Place Bound Top")
		(29 "B.CrtYd" user "Package Geometry/Place Bound Bottom")
		(35 "F.Fab" user "Ref Des/Assembly Top")
		(33 "B.Fab" user "Ref Des/Assembly Bottom")
	)
	(footprint ""
		(layer "B.Cu")
		(at 38.735 -6.6802 -90)
		(property "Reference" "C1"
			(at 0 0 90)
			(layer "B.SilkS")
			(hide yes)
			(effects
				(font
					(size 1.27 1.27)
				)
				(justify mirror)
			)
		)
		(property "Value" "SC1U16V3KX-5GP"
			(at 0 -2.8194 270)
			(unlocked yes)
			(layer "B.Fab")
			(hide yes)
			(effects
				(font
					(size 1.016 1.016)
					(thickness 0.1524)
				)
				(justify mirror)
			)
		)
		(property "Device Type" "C603H36"
			(at 0 -4.3434 270)
			(unlocked yes)
			(layer "B.Fab")
			(hide yes)
			(effects
				(font
					(size 1.016 1.016)
					(thickness 0.1524)
				)
				(justify mirror)
			)
		)
		(duplicate_pad_numbers_are_jumpers no)
		(fp_line
			(start -0.508 0)
			(end 0.508 0)
			(stroke
				(width 0.2032)
				(type default)
			)
			(layer "B.SilkS")
		)
		(fp_rect
			(start 0.5842 1.3335)
			(end -0.5842 -1.3335)
			(stroke
				(width 0)
				(type default)
			)
			(fill no)
			(layer "B.CrtYd")
		)
		(fp_rect
			(start 0.5842 1.3335)
			(end -0.5842 -1.3335)
			(stroke
				(width 0)
				(type default)
			)
			(fill no)
			(layer "B.Fab")
		)
		(pad "1" smd custom
			(at 0 -0.762 90)
			(size 0.2159 0.2159)
			(layers "B.Cu" "B.Mask" "B.Paste")
			(net "P5V_A")
			(options
				(clearance outline)
				(anchor circle)
			)
			(primitives
				(gr_poly
					(pts
						(arc
							(start -0.3302 0.4318)
							(mid -0.402042 0.402042)
							(end -0.4318 0.3302)
						)
						(arc
							(start -0.4318 -0.3302)
							(mid -0.402042 -0.402042)
							(end -0.3302 -0.4318)
						)
						(arc
							(start 0.3302 -0.4318)
							(mid 0.402042 -0.402042)
							(end 0.4318 -0.3302)
						)
						(arc
							(start 0.4318 0.3302)
							(mid 0.402042 0.402042)
							(end 0.3302 0.4318)
						)
					)
					(width 0)
					(fill yes)
				)
			)
		)
		(pad "2" smd custom
			(at 0 0.762 90)
			(size 0.2159 0.2159)
			(layers "B.Cu" "B.Mask" "B.Paste")
			(net "GND")
			(options
				(clearance outline)
				(anchor circle)
			)
			(primitives
				(gr_poly
					(pts
						(arc
							(start -0.3302 0.4318)
							(mid -0.402042 0.402042)
							(end -0.4318 0.3302)
						)
						(arc
							(start -0.4318 -0.3302)
							(mid -0.402042 -0.402042)
							(end -0.3302 -0.4318)
						)
						(arc
							(start 0.3302 -0.4318)
							(mid 0.402042 -0.402042)
							(end 0.4318 -0.3302)
						)
						(arc
							(start 0.4318 0.3302)
							(mid 0.402042 0.402042)
							(end 0.3302 0.4318)
						)
					)
					(width 0)
					(fill yes)
				)
			)
		)
	)
	(footprint ""
		(layer "B.Cu")
		(at 136.0678 -5.9182 180)
		(property "Reference" "R9"
			(at 0 0 0)
			(layer "B.SilkS")
			(hide yes)
			(effects
				(font
					(size 1.27 1.27)
				)
				(justify mirror)
			)
		)
		(property "Value" "130R3F-GP"
			(at 0.0254 -2.5146 180)
			(unlocked yes)
			(layer "B.Fab")
			(hide yes)
			(effects
				(font
					(size 1.016 1.016)
					(thickness 0.1524)
				)
				(justify mirror)
			)
		)
		(property "Device Type" "R603H22"
			(at 0.0254 -4.0386 180)
			(unlocked yes)
			(layer "B.Fab")
			(hide yes)
			(effects
				(font
					(size 1.016 1.016)
					(thickness 0.1524)
				)
				(justify mirror)
			)
		)
		(duplicate_pad_numbers_are_jumpers no)
		(fp_line
			(start 0.4826 0)
			(end 0.2032 0)
			(stroke
				(width 0.2032)
				(type default)
			)
			(layer "B.SilkS")
		)
		(fp_line
			(start -0.2032 0)
			(end -0.4826 0)
			(stroke
				(width 0.2032)
				(type default)
			)
			(layer "B.SilkS")
		)
		(fp_rect
			(start 0.5842 1.3335)
			(end -0.5842 -1.3335)
			(stroke
				(width 0)
				(type default)
			)
			(fill no)
			(layer "B.CrtYd")
		)
		(fp_rect
			(start 0.5842 1.3335)
			(end -0.5842 -1.3335)
			(stroke
				(width 0)
				(type default)
			)
			(fill no)
			(layer "B.Fab")
		)
		(pad "1" smd custom
			(at 0 -0.762)
			(size 0.2159 0.2159)
			(layers "B.Cu" "B.Mask" "B.Paste")
			(net "P5V_A")
			(options
				(clearance outline)
				(anchor circle)
			)
			(primitives
				(gr_poly
					(pts
						(arc
							(start -0.3302 0.4318)
							(mid -0.402042 0.402042)
							(end -0.4318 0.3302)
						)
						(arc
							(start -0.4318 -0.3302)
							(mid -0.402042 -0.402042)
							(end -0.3302 -0.4318)
						)
						(arc
							(start 0.3302 -0.4318)
							(mid 0.402042 -0.402042)
							(end 0.4318 -0.3302)
						)
						(arc
							(start 0.4318 0.3302)
							(mid 0.402042 0.402042)
							(end 0.3302 0.4318)
						)
					)
					(width 0)
					(fill yes)
				)
			)
		)
		(pad "2" smd custom
			(at 0 0.762)
			(size 0.2159 0.2159)
			(layers "B.Cu" "B.Mask" "B.Paste")
			(net "FLT_HDD28_34")
			(options
				(clearance outline)
				(anchor circle)
			)
			(primitives
				(gr_poly
					(pts
						(arc
							(start -0.3302 0.4318)
							(mid -0.402042 0.402042)
							(end -0.4318 0.3302)
						)
						(arc
							(start -0.4318 -0.3302)
							(mid -0.402042 -0.402042)
							(end -0.3302 -0.4318)
						)
						(arc
							(start 0.3302 -0.4318)
							(mid 0.402042 -0.402042)
							(end 0.4318 -0.3302)
						)
						(arc
							(start 0.4318 0.3302)
							(mid 0.402042 0.402042)
							(end 0.3302 0.4318)
						)
					)
					(width 0)
					(fill yes)
				)
			)
		)
	)
	(footprint ""
		(layer "B.Cu")
		(at 29.6418 -2.6416 -90)
		(property "Reference" "R15"
			(at 0 0 90)
			(layer "B.SilkS")
			(hide yes)
			(effects
				(font
					(size 1.27 1.27)
				)
				(justify mirror)
			)
		)
		(property "Value" "4K7R2F-GP"
			(at -0.064008 -3.993896 270)
			(unlocked yes)
			(layer "B.Fab")
			(hide yes)
			(effects
				(font
					(size 1.016 1.016)
					(thickness 0.1524)
				)
				(justify mirror)
			)
		)
		(property "Device Type" "R402H16"
			(at -0.064008 -5.517896 270)
			(unlocked yes)
			(layer "B.Fab")
			(hide yes)
			(effects
				(font
					(size 1.016 1.016)
					(thickness 0.1524)
				)
				(justify mirror)
			)
		)
		(duplicate_pad_numbers_are_jumpers no)
		(fp_line
			(start -0.508 -0.9398)
			(end 0.508 -0.9398)
			(stroke
				(width 0.1524)
				(type default)
			)
			(layer "B.SilkS")
		)
		(fp_line
			(start 0.508 -0.9398)
			(end 0.508 0.9398)
			(stroke
				(width 0.1524)
				(type default)
			)
			(layer "B.SilkS")
		)
		(fp_rect
			(start 0.508 0.9398)
			(end -0.508 -0.9398)
			(stroke
				(width 0)
				(type default)
			)
			(fill no)
			(layer "B.CrtYd")
		)
		(fp_rect
			(start 0.508 0.9398)
			(end -0.508 -0.9398)
			(stroke
				(width 0)
				(type default)
			)
			(fill no)
			(layer "B.Fab")
		)
		(pad "1" smd custom
			(at 0 -0.4445 90)
			(size 0.1397 0.1397)
			(layers "B.Cu" "B.Mask" "B.Paste")
			(net "DRIVE_A_25_31_FLT_LED")
			(options
				(clearance outline)
				(anchor circle)
			)
			(primitives
				(gr_poly
					(pts
						(arc
							(start -0.1778 0.2794)
							(mid -0.249642 0.249642)
							(end -0.2794 0.1778)
						)
						(arc
							(start -0.2794 -0.1778)
							(mid -0.249642 -0.249642)
							(end -0.1778 -0.2794)
						)
						(arc
							(start 0.1778 -0.2794)
							(mid 0.249642 -0.249642)
							(end 0.2794 -0.1778)
						)
						(arc
							(start 0.2794 0.1778)
							(mid 0.249642 0.249642)
							(end 0.1778 0.2794)
						)
					)
					(width 0)
					(fill yes)
				)
			)
		)
		(pad "2" smd custom
			(at 0 0.4445 90)
			(size 0.1397 0.1397)
			(layers "B.Cu" "B.Mask" "B.Paste")
			(net "GND")
			(options
				(clearance outline)
				(anchor circle)
			)
			(primitives
				(gr_poly
					(pts
						(arc
							(start -0.1778 0.2794)
							(mid -0.249642 0.249642)
							(end -0.2794 0.1778)
						)
						(arc
							(start -0.2794 -0.1778)
							(mid -0.249642 -0.249642)
							(end -0.1778 -0.2794)
						)
						(arc
							(start 0.1778 -0.2794)
							(mid 0.249642 -0.249642)
							(end 0.2794 -0.1778)
						)
						(arc
							(start 0.2794 0.1778)
							(mid 0.249642 0.249642)
							(end 0.1778 0.2794)
						)
					)
					(width 0)
					(fill yes)
				)
			)
		)
	)
	(footprint ""
		(layer "B.Cu")
		(at 165.9636 -3.175 -90)
		(property "Reference" "R24"
			(at 0 0 90)
			(layer "B.SilkS")
			(hide yes)
			(effects
				(font
					(size 1.27 1.27)
				)
				(justify mirror)
			)
		)
		(property "Value" "4K7R2F-GP"
			(at -0.064008 -3.993896 270)
			(unlocked yes)
			(layer "B.Fab")
			(hide yes)
			(effects
				(font
					(size 1.016 1.016)
					(thickness 0.1524)
				)
				(justify mirror)
			)
		)
		(property "Device Type" "R402H16"
			(at -0.064008 -5.517896 270)
			(unlocked yes)
			(layer "B.Fab")
			(hide yes)
			(effects
				(font
					(size 1.016 1.016)
					(thickness 0.1524)
				)
				(justify mirror)
			)
		)
		(duplicate_pad_numbers_are_jumpers no)
		(fp_line
			(start -0.508 -0.9398)
			(end 0.508 -0.9398)
			(stroke
				(width 0.1524)
				(type default)
			)
			(layer "B.SilkS")
		)
		(fp_line
			(start 0.508 -0.9398)
			(end 0.508 0.9398)
			(stroke
				(width 0.1524)
				(type default)
			)
			(layer "B.SilkS")
		)
		(fp_rect
			(start 0.508 0.9398)
			(end -0.508 -0.9398)
			(stroke
				(width 0)
				(type default)
			)
			(fill no)
			(layer "B.CrtYd")
		)
		(fp_rect
			(start 0.508 0.9398)
			(end -0.508 -0.9398)
			(stroke
				(width 0)
				(type default)
			)
			(fill no)
			(layer "B.Fab")
		)
		(pad "1" smd custom
			(at 0 -0.4445 90)
			(size 0.1397 0.1397)
			(layers "B.Cu" "B.Mask" "B.Paste")
			(net "DRIVE_A_29_35_ACT")
			(options
				(clearance outline)
				(anchor circle)
			)
			(primitives
				(gr_poly
					(pts
						(arc
							(start -0.1778 0.2794)
							(mid -0.249642 0.249642)
							(end -0.2794 0.1778)
						)
						(arc
							(start -0.2794 -0.1778)
							(mid -0.249642 -0.249642)
							(end -0.1778 -0.2794)
						)
						(arc
							(start 0.1778 -0.2794)
							(mid 0.249642 -0.249642)
							(end 0.2794 -0.1778)
						)
						(arc
							(start 0.2794 0.1778)
							(mid 0.249642 0.249642)
							(end 0.1778 0.2794)
						)
					)
					(width 0)
					(fill yes)
				)
			)
		)
		(pad "2" smd custom
			(at 0 0.4445 90)
			(size 0.1397 0.1397)
			(layers "B.Cu" "B.Mask" "B.Paste")
			(net "GND")
			(options
				(clearance outline)
				(anchor circle)
			)
			(primitives
				(gr_poly
					(pts
						(arc
							(start -0.1778 0.2794)
							(mid -0.249642 0.249642)
							(end -0.2794 0.1778)
						)
						(arc
							(start -0.2794 -0.1778)
							(mid -0.249642 -0.249642)
							(end -0.1778 -0.2794)
						)
						(arc
							(start 0.1778 -0.2794)
							(mid 0.249642 -0.249642)
							(end 0.2794 -0.1778)
						)
						(arc
							(start 0.2794 0.1778)
							(mid 0.249642 0.249642)
							(end 0.1778 0.2794)
						)
					)
					(width 0)
					(fill yes)
				)
			)
		)
	)
	(footprint ""
		(layer "B.Cu")
		(at 22.8854 -2.9972 -90)
		(property "Reference" "R14"
			(at 0 0 90)
			(layer "B.SilkS")
			(hide yes)
			(effects
				(font
					(size 1.27 1.27)
				)
				(justify mirror)
			)
		)
		(property "Value" "4K7R2F-GP"
			(at -0.064008 -3.993896 270)
			(unlocked yes)
			(layer "B.Fab")
			(hide yes)
			(effects
				(font
					(size 1.016 1.016)
					(thickness 0.1524)
				)
				(justify mirror)
			)
		)
		(property "Device Type" "R402H16"
			(at -0.064008 -5.517896 270)
			(unlocked yes)
			(layer "B.Fab")
			(hide yes)
			(effects
				(font
					(size 1.016 1.016)
					(thickness 0.1524)
				)
				(justify mirror)
			)
		)
		(duplicate_pad_numbers_are_jumpers no)
		(fp_line
			(start -0.508 -0.9398)
			(end 0.508 -0.9398)
			(stroke
				(width 0.1524)
				(type default)
			)
			(layer "B.SilkS")
		)
		(fp_line
			(start 0.508 -0.9398)
			(end 0.508 0.9398)
			(stroke
				(width 0.1524)
				(type default)
			)
			(layer "B.SilkS")
		)
		(fp_rect
			(start 0.508 0.9398)
			(end -0.508 -0.9398)
			(stroke
				(width 0)
				(type default)
			)
			(fill no)
			(layer "B.CrtYd")
		)
		(fp_rect
			(start 0.508 0.9398)
			(end -0.508 -0.9398)
			(stroke
				(width 0)
				(type default)
			)
			(fill no)
			(layer "B.Fab")
		)
		(pad "1" smd custom
			(at 0 -0.4445 90)
			(size 0.1397 0.1397)
			(layers "B.Cu" "B.Mask" "B.Paste")
			(net "DRIVE_A_24_30_ACT")
			(options
				(clearance outline)
				(anchor circle)
			)
			(primitives
				(gr_poly
					(pts
						(arc
							(start -0.1778 0.2794)
							(mid -0.249642 0.249642)
							(end -0.2794 0.1778)
						)
						(arc
							(start -0.2794 -0.1778)
							(mid -0.249642 -0.249642)
							(end -0.1778 -0.2794)
						)
						(arc
							(start 0.1778 -0.2794)
							(mid 0.249642 -0.249642)
							(end 0.2794 -0.1778)
						)
						(arc
							(start 0.2794 0.1778)
							(mid 0.249642 0.249642)
							(end 0.1778 0.2794)
						)
					)
					(width 0)
					(fill yes)
				)
			)
		)
		(pad "2" smd custom
			(at 0 0.4445 90)
			(size 0.1397 0.1397)
			(layers "B.Cu" "B.Mask" "B.Paste")
			(net "GND")
			(options
				(clearance outline)
				(anchor circle)
			)
			(primitives
				(gr_poly
					(pts
						(arc
							(start -0.1778 0.2794)
							(mid -0.249642 0.249642)
							(end -0.2794 0.1778)
						)
						(arc
							(start -0.2794 -0.1778)
							(mid -0.249642 -0.249642)
							(end -0.1778 -0.2794)
						)
						(arc
							(start 0.1778 -0.2794)
							(mid 0.249642 -0.249642)
							(end 0.2794 -0.1778)
						)
						(arc
							(start 0.2794 0.1778)
							(mid 0.249642 0.249642)
							(end 0.1778 0.2794)
						)
					)
					(width 0)
					(fill yes)
				)
			)
		)
	)
	(footprint ""
		(layer "B.Cu")
		(at 64.797178 -5.652516)
		(property "Reference" "Q6"
			(at 0 0 0)
			(layer "B.SilkS")
			(hide yes)
			(effects
				(font
					(size 1.27 1.27)
				)
				(justify mirror)
			)
		)
		(property "Value" "SSM3K324R-GP"
			(at -0.127 -8.9662 0)
			(unlocked yes)
			(layer "B.Fab")
			(hide yes)
			(effects
				(font
					(size 1.016 1.016)
					(thickness 0.1524)
				)
				(justify mirror)
			)
		)
		(property "Device Type" "SOT23DGS2D4H35"
			(at -0.127 -10.4902 0)
			(unlocked yes)
			(layer "B.Fab")
			(hide yes)
			(effects
				(font
					(size 1.016 1.016)
					(thickness 0.1524)
				)
				(justify mirror)
			)
		)
		(duplicate_pad_numbers_are_jumpers no)
		(fp_line
			(start -1.651 -1.778)
			(end 1.651 -1.778)
			(stroke
				(width 0.1524)
				(type default)
			)
			(layer "B.SilkS")
		)
		(fp_line
			(start -1.651 1.778)
			(end -1.651 -1.778)
			(stroke
				(width 0.1524)
				(type default)
			)
			(layer "B.SilkS")
		)
		(fp_line
			(start 1.651 -1.778)
			(end 1.651 1.778)
			(stroke
				(width 0.1524)
				(type default)
			)
			(layer "B.SilkS")
		)
		(fp_line
			(start 1.651 1.778)
			(end -1.651 1.778)
			(stroke
				(width 0.1524)
				(type default)
			)
			(layer "B.SilkS")
		)
		(fp_poly
			(pts
				(xy 1.778 1.8796) (xy 1.778 -1.8796) (xy -1.778 -1.8796) (xy -1.778 1.8796)
			)
			(stroke
				(width 0)
				(type default)
			)
			(fill no)
			(layer "B.CrtYd")
		)
		(fp_poly
			(pts
				(xy 1.778 1.8796) (xy 1.778 -1.8796) (xy -1.778 -1.8796) (xy -1.778 1.8796)
			)
			(stroke
				(width 0)
				(type default)
			)
			(fill no)
			(layer "B.Fab")
		)
		(pad "D" smd custom
			(at 0 -0.9525 180)
			(size 0.1905 0.1905)
			(layers "B.Cu" "B.Mask" "B.Paste")
			(net "DRV_ACT_26_32_N")
			(options
				(clearance outline)
				(anchor circle)
			)
			(primitives
				(gr_poly
					(pts
						(arc
							(start -0.1778 -0.5715)
							(mid -0.321484 -0.511984)
							(end -0.381 -0.3683)
						)
						(arc
							(start -0.381 0.3683)
							(mid -0.321484 0.511984)
							(end -0.1778 0.5715)
						)
						(arc
							(start 0.1778 0.5715)
							(mid 0.321484 0.511984)
							(end 0.381 0.3683)
						)
						(arc
							(start 0.381 -0.3683)
							(mid 0.321484 -0.511984)
							(end 0.1778 -0.5715)
						)
					)
					(width 0)
					(fill yes)
				)
			)
		)
		(pad "G" smd custom
			(at 0.98425 0.9525 180)
			(size 0.1905 0.1905)
			(layers "B.Cu" "B.Mask" "B.Paste")
			(net "DRIVE_A_26_32_ACT")
			(options
				(clearance outline)
				(anchor circle)
			)
			(primitives
				(gr_poly
					(pts
						(arc
							(start -0.1778 -0.5715)
							(mid -0.321484 -0.511984)
							(end -0.381 -0.3683)
						)
						(arc
							(start -0.381 0.3683)
							(mid -0.321484 0.511984)
							(end -0.1778 0.5715)
						)
						(arc
							(start 0.1778 0.5715)
							(mid 0.321484 0.511984)
							(end 0.381 0.3683)
						)
						(arc
							(start 0.381 -0.3683)
							(mid 0.321484 -0.511984)
							(end 0.1778 -0.5715)
						)
					)
					(width 0)
					(fill yes)
				)
			)
		)
		(pad "S" smd custom
			(at -0.98425 0.9525 180)
			(size 0.1905 0.1905)
			(layers "B.Cu" "B.Mask" "B.Paste")
			(net "GND")
			(options
				(clearance outline)
				(anchor circle)
			)
			(primitives
				(gr_poly
					(pts
						(arc
							(start -0.1778 -0.5715)
							(mid -0.321484 -0.511984)
							(end -0.381 -0.3683)
						)
						(arc
							(start -0.381 0.3683)
							(mid -0.321484 0.511984)
							(end -0.1778 0.5715)
						)
						(arc
							(start 0.1778 0.5715)
							(mid 0.321484 0.511984)
							(end 0.381 0.3683)
						)
						(arc
							(start 0.381 -0.3683)
							(mid 0.321484 -0.511984)
							(end 0.1778 -0.5715)
						)
					)
					(width 0)
					(fill yes)
				)
			)
		)
	)
	(footprint ""
		(layer "B.Cu")
		(at 68.636388 -3.247644 -90)
		(property "Reference" "R17"
			(at 0 0 90)
			(layer "B.SilkS")
			(hide yes)
			(effects
				(font
					(size 1.27 1.27)
				)
				(justify mirror)
			)
		)
		(property "Value" "4K7R2F-GP"
			(at -0.064008 -3.993896 270)
			(unlocked yes)
			(layer "B.Fab")
			(hide yes)
			(effects
				(font
					(size 1.016 1.016)
					(thickness 0.1524)
				)
				(justify mirror)
			)
		)
		(property "Device Type" "R402H16"
			(at -0.064008 -5.517896 270)
			(unlocked yes)
			(layer "B.Fab")
			(hide yes)
			(effects
				(font
					(size 1.016 1.016)
					(thickness 0.1524)
				)
				(justify mirror)
			)
		)
		(duplicate_pad_numbers_are_jumpers no)
		(fp_line
			(start -0.508 -0.9398)
			(end 0.508 -0.9398)
			(stroke
				(width 0.1524)
				(type default)
			)
			(layer "B.SilkS")
		)
		(fp_line
			(start 0.508 -0.9398)
			(end 0.508 0.9398)
			(stroke
				(width 0.1524)
				(type default)
			)
			(layer "B.SilkS")
		)
		(fp_rect
			(start 0.508 0.9398)
			(end -0.508 -0.9398)
			(stroke
				(width 0)
				(type default)
			)
			(fill no)
			(layer "B.CrtYd")
		)
		(fp_rect
			(start 0.508 0.9398)
			(end -0.508 -0.9398)
			(stroke
				(width 0)
				(type default)
			)
			(fill no)
			(layer "B.Fab")
		)
		(pad "1" smd custom
			(at 0 -0.4445 90)
			(size 0.1397 0.1397)
			(layers "B.Cu" "B.Mask" "B.Paste")
			(net "DRIVE_A_26_32_FLT_LED")
			(options
				(clearance outline)
				(anchor circle)
			)
			(primitives
				(gr_poly
					(pts
						(arc
							(start -0.1778 0.2794)
							(mid -0.249642 0.249642)
							(end -0.2794 0.1778)
						)
						(arc
							(start -0.2794 -0.1778)
							(mid -0.249642 -0.249642)
							(end -0.1778 -0.2794)
						)
						(arc
							(start 0.1778 -0.2794)
							(mid 0.249642 -0.249642)
							(end 0.2794 -0.1778)
						)
						(arc
							(start 0.2794 0.1778)
							(mid 0.249642 0.249642)
							(end 0.1778 0.2794)
						)
					)
					(width 0)
					(fill yes)
				)
			)
		)
		(pad "2" smd custom
			(at 0 0.4445 90)
			(size 0.1397 0.1397)
			(layers "B.Cu" "B.Mask" "B.Paste")
			(net "GND")
			(options
				(clearance outline)
				(anchor circle)
			)
			(primitives
				(gr_poly
					(pts
						(arc
							(start -0.1778 0.2794)
							(mid -0.249642 0.249642)
							(end -0.2794 0.1778)
						)
						(arc
							(start -0.2794 -0.1778)
							(mid -0.249642 -0.249642)
							(end -0.1778 -0.2794)
						)
						(arc
							(start 0.1778 -0.2794)
							(mid 0.249642 -0.249642)
							(end 0.2794 -0.1778)
						)
						(arc
							(start 0.2794 0.1778)
							(mid 0.249642 0.249642)
							(end 0.1778 0.2794)
						)
					)
					(width 0)
					(fill yes)
				)
			)
		)
	)
)
